(kicad_pcb
	(version 20260206)
	(generator "pcbnew")
	(generator_version "10.0")
	(general
		(thickness 1.6)
		(legacy_teardrops no)
	)
	(paper "A4")
	(title_block
		(title "baseboard — 13948-1b.1110WZS1818.brd")
		(comment 1 "Honey Badger (Wiwynn) / footprints 489-494 of 2523")
	)
	(layers
		(0 "F.Cu" signal "TOP")
		(4 "In1.Cu" signal "L2GND")
		(6 "In2.Cu" signal "L3")
		(8 "In3.Cu" signal "L4VCC")
		(10 "In4.Cu" signal "L5VCC")
		(12 "In5.Cu" signal "L6")
		(14 "In6.Cu" signal "L7GND")
		(2 "B.Cu" signal "BOTTOM")
		(9 "F.Adhes" user "F.Adhesive")
		(11 "B.Adhes" user "B.Adhesive")
		(13 "F.Paste" user "Package Geometry/Pastemask Top")
		(15 "B.Paste" user "Package Geometry/Pastemask Bottom")
		(5 "F.SilkS" user "Ref Des/Silkscreen Top")
		(7 "B.SilkS" user "Ref Des/Silkscreen Bottom")
		(1 "F.Mask" user "Board Geometry/Soldermask Top")
		(3 "B.Mask" user "Board Geometry/Soldermask Bottom")
		(17 "Dwgs.User" user "User.Drawings")
		(19 "Cmts.User" user "User.Comments")
		(21 "Eco1.User" user "User.Eco1")
		(23 "Eco2.User" user "User.Eco2")
		(25 "Edge.Cuts" user "Board Geometry/Outline")
		(27 "Margin" user)
		(31 "F.CrtYd" user "Package Geometry/Place Bound Top")
		(29 "B.CrtYd" user "Package Geometry/Place Bound Bottom")
		(35 "F.Fab" user "Ref Des/Assembly Top")
		(33 "B.Fab" user "Ref Des/Assembly Bottom")
	)
	(footprint ""
		(layer "F.Cu")
		(at 201.250296 -86.372192)
		(property "Reference" "SC1132"
			(at 0 0 0)
			(layer "F.SilkS")
			(hide yes)
			(effects
				(font
					(size 1.27 1.27)
				)
			)
		)
		(property "Value" "SC100U6D3V0MX-2GP"
			(at -0.00254 -4.78536 0)
			(unlocked yes)
			(layer "F.Fab")
			(hide yes)
			(effects
				(font
					(size 1.016 1.016)
					(thickness 0.1524)
				)
			)
		)
		(property "Device Type" "C1210H107"
			(at -0.00254 -6.38048 0)
			(unlocked yes)
			(layer "F.Fab")
			(hide yes)
			(effects
				(font
					(size 1.016 1.016)
					(thickness 0.1524)
				)
			)
		)
		(duplicate_pad_numbers_are_jumpers no)
		(fp_line
			(start -1.5748 -2.3368)
			(end -1.5748 -0.762)
			(stroke
				(width 0.1524)
				(type default)
			)
			(layer "F.SilkS")
		)
		(fp_line
			(start -1.5748 0.762)
			(end -1.5748 2.3368)
			(stroke
				(width 0.1524)
				(type default)
			)
			(layer "F.SilkS")
		)
		(fp_line
			(start -1.5748 2.3368)
			(end 1.5748 2.3368)
			(stroke
				(width 0.1524)
				(type default)
			)
			(layer "F.SilkS")
		)
		(fp_line
			(start 1.5748 -2.3368)
			(end -1.5748 -2.3368)
			(stroke
				(width 0.1524)
				(type default)
			)
			(layer "F.SilkS")
		)
		(fp_line
			(start 1.5748 -0.762)
			(end 1.5748 -2.3368)
			(stroke
				(width 0.1524)
				(type default)
			)
			(layer "F.SilkS")
		)
		(fp_line
			(start 1.5748 2.3368)
			(end 1.5748 0.762)
			(stroke
				(width 0.1524)
				(type default)
			)
			(layer "F.SilkS")
		)
		(fp_rect
			(start -1.651 2.413)
			(end 1.651 -2.413)
			(stroke
				(width 0)
				(type default)
			)
			(fill no)
			(layer "F.CrtYd")
		)
		(fp_poly
			(pts
				(xy 1.651 2.413) (xy 1.651 -2.413) (xy -1.651 -2.413) (xy -1.651 2.413)
			)
			(stroke
				(width 0)
				(type default)
			)
			(fill no)
			(layer "F.Fab")
		)
		(pad "1" smd rect
			(at 0 -1.4732)
			(size 2.794 1.397)
			(layers "F.Cu" "F.Mask" "F.Paste")
			(net "GND")
		)
		(pad "2" smd rect
			(at 0 1.4732)
			(size 2.794 1.397)
			(layers "F.Cu" "F.Mask" "F.Paste")
			(net "GB_VDDH2")
		)
	)
	(footprint ""
		(layer "F.Cu")
		(at 83.8708 -3.683)
		(property "Reference" "PC198"
			(at 0 0 0)
			(layer "F.SilkS")
			(hide yes)
			(effects
				(font
					(size 1.27 1.27)
				)
			)
		)
		(property "Value" "SC22U6D3V6KX-2-GP"
			(at -0.0762 -5.1308 0)
			(unlocked yes)
			(layer "F.Fab")
			(hide yes)
			(effects
				(font
					(size 1.016 1.016)
					(thickness 0.1524)
				)
			)
		)
		(property "Device Type" "C1206H71"
			(at -0.127 -6.6548 0)
			(unlocked yes)
			(layer "F.Fab")
			(hide yes)
			(effects
				(font
					(size 1.016 1.016)
					(thickness 0.1524)
				)
			)
		)
		(duplicate_pad_numbers_are_jumpers no)
		(fp_line
			(start -1.016 -2.2352)
			(end 1.016 -2.2352)
			(stroke
				(width 0.1524)
				(type default)
			)
			(layer "F.SilkS")
		)
		(fp_line
			(start -1.016 -0.8382)
			(end -1.016 -2.2352)
			(stroke
				(width 0.1524)
				(type default)
			)
			(layer "F.SilkS")
		)
		(fp_line
			(start -1.016 2.2352)
			(end -1.016 0.8382)
			(stroke
				(width 0.1524)
				(type default)
			)
			(layer "F.SilkS")
		)
		(fp_line
			(start 1.016 -2.2352)
			(end 1.016 -0.8382)
			(stroke
				(width 0.1524)
				(type default)
			)
			(layer "F.SilkS")
		)
		(fp_line
			(start 1.016 0.8382)
			(end 1.016 2.2352)
			(stroke
				(width 0.1524)
				(type default)
			)
			(layer "F.SilkS")
		)
		(fp_line
			(start 1.016 2.2352)
			(end -1.016 2.2352)
			(stroke
				(width 0.1524)
				(type default)
			)
			(layer "F.SilkS")
		)
		(fp_rect
			(start -1.0922 2.3114)
			(end 1.0922 -2.3114)
			(stroke
				(width 0)
				(type default)
			)
			(fill no)
			(layer "F.CrtYd")
		)
		(fp_poly
			(pts
				(xy 1.0922 -2.3114) (xy 1.0922 2.3114) (xy -1.0922 2.3114) (xy -1.0922 -2.3114)
			)
			(stroke
				(width 0)
				(type default)
			)
			(fill no)
			(layer "F.Fab")
		)
		(pad "1" smd rect
			(at 0 -1.397)
			(size 1.651 1.27)
			(layers "F.Cu" "F.Mask" "F.Paste")
			(net "P0V955_C")
		)
		(pad "2" smd rect
			(at 0 1.397)
			(size 1.651 1.27)
			(layers "F.Cu" "F.Mask" "F.Paste")
			(net "GND")
		)
	)
	(footprint ""
		(layer "F.Cu")
		(at 299.212 -91.948 180)
		(property "Reference" "R159"
			(at 0 0 180)
			(layer "F.SilkS")
			(hide yes)
			(effects
				(font
					(size 1.27 1.27)
				)
			)
		)
		(property "Value" "0R2J-2-GP"
			(at 0.064008 -3.993896 180)
			(unlocked yes)
			(layer "F.Fab")
			(hide yes)
			(effects
				(font
					(size 1.016 1.016)
					(thickness 0.1524)
				)
			)
		)
		(property "Device Type" "R402H16"
			(at 0.064008 -5.517896 180)
			(unlocked yes)
			(layer "F.Fab")
			(hide yes)
			(effects
				(font
					(size 1.016 1.016)
					(thickness 0.1524)
				)
			)
		)
		(duplicate_pad_numbers_are_jumpers no)
		(fp_line
			(start 0.508 -0.9398)
			(end -0.508 -0.9398)
			(stroke
				(width 0.1524)
				(type default)
			)
			(layer "F.SilkS")
		)
		(fp_line
			(start -0.508 -0.9398)
			(end -0.508 0.9398)
			(stroke
				(width 0.1524)
				(type default)
			)
			(layer "F.SilkS")
		)
		(fp_rect
			(start -0.508 0.9398)
			(end 0.508 -0.9398)
			(stroke
				(width 0)
				(type default)
			)
			(fill no)
			(layer "F.CrtYd")
		)
		(fp_rect
			(start -0.508 0.9398)
			(end 0.508 -0.9398)
			(stroke
				(width 0)
				(type default)
			)
			(fill no)
			(layer "F.Fab")
		)
		(pad "1" smd custom
			(at 0 -0.4445 180)
			(size 0.1397 0.1397)
			(layers "F.Cu" "F.Mask" "F.Paste")
			(net "BMC_I2C_D_SDA")
			(options
				(clearance outline)
				(anchor circle)
			)
			(primitives
				(gr_poly
					(pts
						(arc
							(start -0.1778 -0.2794)
							(mid -0.249642 -0.249642)
							(end -0.2794 -0.1778)
						)
						(arc
							(start -0.2794 0.1778)
							(mid -0.249642 0.249642)
							(end -0.1778 0.2794)
						)
						(arc
							(start 0.1778 0.2794)
							(mid 0.249642 0.249642)
							(end 0.2794 0.1778)
						)
						(arc
							(start 0.2794 -0.1778)
							(mid 0.249642 -0.249642)
							(end 0.1778 -0.2794)
						)
					)
					(width 0)
					(fill yes)
				)
			)
		)
		(pad "2" smd custom
			(at 0 0.4445 180)
			(size 0.1397 0.1397)
			(layers "F.Cu" "F.Mask" "F.Paste")
			(net "TEMP_2_SDA")
			(options
				(clearance outline)
				(anchor circle)
			)
			(primitives
				(gr_poly
					(pts
						(arc
							(start -0.1778 -0.2794)
							(mid -0.249642 -0.249642)
							(end -0.2794 -0.1778)
						)
						(arc
							(start -0.2794 0.1778)
							(mid -0.249642 0.249642)
							(end -0.1778 0.2794)
						)
						(arc
							(start 0.1778 0.2794)
							(mid 0.249642 0.249642)
							(end 0.2794 0.1778)
						)
						(arc
							(start 0.2794 -0.1778)
							(mid 0.249642 -0.249642)
							(end 0.1778 -0.2794)
						)
					)
					(width 0)
					(fill yes)
				)
			)
		)
	)
	(footprint ""
		(layer "F.Cu")
		(at 189.927992 -46.609)
		(property "Reference" "Q8"
			(at 0 0 0)
			(layer "F.SilkS")
			(hide yes)
			(effects
				(font
					(size 1.27 1.27)
				)
			)
		)
		(property "Value" "2N7002A-7-GP"
			(at 0.127 -8.9662 0)
			(unlocked yes)
			(layer "F.Fab")
			(hide yes)
			(effects
				(font
					(size 1.016 1.016)
					(thickness 0.1524)
				)
			)
		)
		(property "Device Type" "SOT23DGS2D4H48"
			(at 0.127 -10.4902 0)
			(unlocked yes)
			(layer "F.Fab")
			(hide yes)
			(effects
				(font
					(size 1.016 1.016)
					(thickness 0.1524)
				)
			)
		)
		(duplicate_pad_numbers_are_jumpers no)
		(fp_line
			(start -1.651 -1.778)
			(end -1.651 1.778)
			(stroke
				(width 0.1524)
				(type default)
			)
			(layer "F.SilkS")
		)
		(fp_line
			(start -1.651 1.778)
			(end 1.651 1.778)
			(stroke
				(width 0.1524)
				(type default)
			)
			(layer "F.SilkS")
		)
		(fp_line
			(start 1.651 -1.778)
			(end -1.651 -1.778)
			(stroke
				(width 0.1524)
				(type default)
			)
			(layer "F.SilkS")
		)
		(fp_line
			(start 1.651 1.778)
			(end 1.651 -1.778)
			(stroke
				(width 0.1524)
				(type default)
			)
			(layer "F.SilkS")
		)
		(fp_poly
			(pts
				(xy -1.778 1.8796) (xy -1.778 -1.8796) (xy 1.778 -1.8796) (xy 1.778 1.8796)
			)
			(stroke
				(width 0)
				(type default)
			)
			(fill no)
			(layer "F.CrtYd")
		)
		(fp_poly
			(pts
				(xy -1.778 1.8796) (xy -1.778 -1.8796) (xy 1.778 -1.8796) (xy 1.778 1.8796)
			)
			(stroke
				(width 0)
				(type default)
			)
			(fill no)
			(layer "F.Fab")
		)
		(pad "D" smd custom
			(at 0 -0.9525)
			(size 0.1905 0.1905)
			(layers "F.Cu" "F.Mask" "F.Paste")
			(net "PRSNT_MSB_AND_1")
			(options
				(clearance outline)
				(anchor circle)
			)
			(primitives
				(gr_poly
					(pts
						(arc
							(start -0.1778 0.5715)
							(mid -0.321484 0.511984)
							(end -0.381 0.3683)
						)
						(arc
							(start -0.381 -0.3683)
							(mid -0.321484 -0.511984)
							(end -0.1778 -0.5715)
						)
						(arc
							(start 0.1778 -0.5715)
							(mid 0.321484 -0.511984)
							(end 0.381 -0.3683)
						)
						(arc
							(start 0.381 0.3683)
							(mid 0.321484 0.511984)
							(end 0.1778 0.5715)
						)
					)
					(width 0)
					(fill yes)
				)
			)
		)
		(pad "G" smd custom
			(at -0.98425 0.9525)
			(size 0.1905 0.1905)
			(layers "F.Cu" "F.Mask" "F.Paste")
			(net "PRSNT_MSB_A1")
			(options
				(clearance outline)
				(anchor circle)
			)
			(primitives
				(gr_poly
					(pts
						(arc
							(start -0.1778 0.5715)
							(mid -0.321484 0.511984)
							(end -0.381 0.3683)
						)
						(arc
							(start -0.381 -0.3683)
							(mid -0.321484 -0.511984)
							(end -0.1778 -0.5715)
						)
						(arc
							(start 0.1778 -0.5715)
							(mid 0.321484 -0.511984)
							(end 0.381 -0.3683)
						)
						(arc
							(start 0.381 0.3683)
							(mid 0.321484 0.511984)
							(end 0.1778 0.5715)
						)
					)
					(width 0)
					(fill yes)
				)
			)
		)
		(pad "S" smd custom
			(at 0.98425 0.9525)
			(size 0.1905 0.1905)
			(layers "F.Cu" "F.Mask" "F.Paste")
			(net "GND")
			(options
				(clearance outline)
				(anchor circle)
			)
			(primitives
				(gr_poly
					(pts
						(arc
							(start -0.1778 0.5715)
							(mid -0.321484 0.511984)
							(end -0.381 0.3683)
						)
						(arc
							(start -0.381 -0.3683)
							(mid -0.321484 -0.511984)
							(end -0.1778 -0.5715)
						)
						(arc
							(start 0.1778 -0.5715)
							(mid 0.321484 -0.511984)
							(end 0.381 -0.3683)
						)
						(arc
							(start 0.381 0.3683)
							(mid 0.321484 0.511984)
							(end 0.1778 0.5715)
						)
					)
					(width 0)
					(fill yes)
				)
			)
		)
	)
	(footprint ""
		(layer "F.Cu")
		(at 276.348952 -188.880496)
		(property "Reference" "R297"
			(at 0 0 0)
			(layer "F.SilkS")
			(hide yes)
			(effects
				(font
					(size 1.27 1.27)
				)
			)
		)
		(property "Value" "4K7R2F-GP"
			(at 0.064008 -3.993896 0)
			(unlocked yes)
			(layer "F.Fab")
			(hide yes)
			(effects
				(font
					(size 1.016 1.016)
					(thickness 0.1524)
				)
			)
		)
		(property "Device Type" "R402H16"
			(at 0.064008 -5.517896 0)
			(unlocked yes)
			(layer "F.Fab")
			(hide yes)
			(effects
				(font
					(size 1.016 1.016)
					(thickness 0.1524)
				)
			)
		)
		(duplicate_pad_numbers_are_jumpers no)
		(fp_line
			(start -0.508 -0.9398)
			(end -0.508 0.9398)
			(stroke
				(width 0.1524)
				(type default)
			)
			(layer "F.SilkS")
		)
		(fp_line
			(start 0.508 -0.9398)
			(end -0.508 -0.9398)
			(stroke
				(width 0.1524)
				(type default)
			)
			(layer "F.SilkS")
		)
		(fp_rect
			(start -0.508 0.9398)
			(end 0.508 -0.9398)
			(stroke
				(width 0)
				(type default)
			)
			(fill no)
			(layer "F.CrtYd")
		)
		(fp_rect
			(start -0.508 0.9398)
			(end 0.508 -0.9398)
			(stroke
				(width 0)
				(type default)
			)
			(fill no)
			(layer "F.Fab")
		)
		(pad "1" smd custom
			(at 0 -0.4445)
			(size 0.1397 0.1397)
			(layers "F.Cu" "F.Mask" "F.Paste")
			(net "P3V3_STBY")
			(options
				(clearance outline)
				(anchor circle)
			)
			(primitives
				(gr_poly
					(pts
						(arc
							(start -0.1778 -0.2794)
							(mid -0.249642 -0.249642)
							(end -0.2794 -0.1778)
						)
						(arc
							(start -0.2794 0.1778)
							(mid -0.249642 0.249642)
							(end -0.1778 0.2794)
						)
						(arc
							(start 0.1778 0.2794)
							(mid 0.249642 0.249642)
							(end 0.2794 0.1778)
						)
						(arc
							(start 0.2794 -0.1778)
							(mid 0.249642 -0.249642)
							(end 0.1778 -0.2794)
						)
					)
					(width 0)
					(fill yes)
				)
			)
		)
		(pad "2" smd custom
			(at 0 0.4445)
			(size 0.1397 0.1397)
			(layers "F.Cu" "F.Mask" "F.Paste")
			(net "OSC2_CONT")
			(options
				(clearance outline)
				(anchor circle)
			)
			(primitives
				(gr_poly
					(pts
						(arc
							(start -0.1778 -0.2794)
							(mid -0.249642 -0.249642)
							(end -0.2794 -0.1778)
						)
						(arc
							(start -0.2794 0.1778)
							(mid -0.249642 0.249642)
							(end -0.1778 0.2794)
						)
						(arc
							(start 0.1778 0.2794)
							(mid 0.249642 0.249642)
							(end 0.2794 0.1778)
						)
						(arc
							(start 0.2794 -0.1778)
							(mid 0.249642 -0.249642)
							(end 0.1778 -0.2794)
						)
					)
					(width 0)
					(fill yes)
				)
			)
		)
	)
	(footprint ""
		(layer "F.Cu")
		(at 274.193 -160.401 90)
		(property "Reference" "R234"
			(at 0 0 90)
			(layer "F.SilkS")
			(hide yes)
			(effects
				(font
					(size 1.27 1.27)
				)
			)
		)
		(property "Value" "100KR2F-L1-GP"
			(at 0.064008 -3.993896 90)
			(unlocked yes)
			(layer "F.Fab")
			(hide yes)
			(effects
				(font
					(size 1.016 1.016)
					(thickness 0.1524)
				)
			)
		)
		(property "Device Type" "R402H16"
			(at 0.064008 -5.517896 90)
			(unlocked yes)
			(layer "F.Fab")
			(hide yes)
			(effects
				(font
					(size 1.016 1.016)
					(thickness 0.1524)
				)
			)
		)
		(duplicate_pad_numbers_are_jumpers no)
		(fp_line
			(start 0.508 -0.9398)
			(end -0.508 -0.9398)
			(stroke
				(width 0.1524)
				(type default)
			)
			(layer "F.SilkS")
		)
		(fp_line
			(start -0.508 -0.9398)
			(end -0.508 0.9398)
			(stroke
				(width 0.1524)
				(type default)
			)
			(layer "F.SilkS")
		)
		(fp_rect
			(start -0.508 0.9398)
			(end 0.508 -0.9398)
			(stroke
				(width 0)
				(type default)
			)
			(fill no)
			(layer "F.CrtYd")
		)
		(fp_rect
			(start -0.508 0.9398)
			(end 0.508 -0.9398)
			(stroke
				(width 0)
				(type default)
			)
			(fill no)
			(layer "F.Fab")
		)
		(pad "1" smd custom
			(at 0 -0.4445 90)
			(size 0.1397 0.1397)
			(layers "F.Cu" "F.Mask" "F.Paste")
			(net "GND")
			(options
				(clearance outline)
				(anchor circle)
			)
			(primitives
				(gr_poly
					(pts
						(arc
							(start -0.1778 -0.2794)
							(mid -0.249642 -0.249642)
							(end -0.2794 -0.1778)
						)
						(arc
							(start -0.2794 0.1778)
							(mid -0.249642 0.249642)
							(end -0.1778 0.2794)
						)
						(arc
							(start 0.1778 0.2794)
							(mid 0.249642 0.249642)
							(end 0.2794 0.1778)
						)
						(arc
							(start 0.2794 -0.1778)
							(mid 0.249642 -0.249642)
							(end 0.1778 -0.2794)
						)
					)
					(width 0)
					(fill yes)
				)
			)
		)
		(pad "2" smd custom
			(at 0 0.4445 90)
			(size 0.1397 0.1397)
			(layers "F.Cu" "F.Mask" "F.Paste")
			(net "TP_BMC0_LPC_LAD0")
			(options
				(clearance outline)
				(anchor circle)
			)
			(primitives
				(gr_poly
					(pts
						(arc
							(start -0.1778 -0.2794)
							(mid -0.249642 -0.249642)
							(end -0.2794 -0.1778)
						)
						(arc
							(start -0.2794 0.1778)
							(mid -0.249642 0.249642)
							(end -0.1778 0.2794)
						)
						(arc
							(start 0.1778 0.2794)
							(mid 0.249642 0.249642)
							(end 0.2794 0.1778)
						)
						(arc
							(start 0.2794 -0.1778)
							(mid 0.249642 -0.249642)
							(end 0.1778 -0.2794)
						)
					)
					(width 0)
					(fill yes)
				)
			)
		)
	)
)
